(kicad_pcb
	(version 20241229)
	(generator "pcbnew")
	(generator_version "9.0")
	(general
		(thickness 1.292)
		(legacy_teardrops no)
	)
	(paper "A4")
	(title_block
		(title "LPDDR5 Testbed")
		(date "2023-12-19")
		(rev "1.0.0")
		(comment 9 "footprints 59-65 of 160")
	)
	(layers
		(0 "F.Cu" signal)
		(4 "In1.Cu" power)
		(6 "In2.Cu" power)
		(8 "In3.Cu" signal)
		(10 "In4.Cu" signal)
		(2 "B.Cu" signal)
		(9 "F.Adhes" user "F.Adhesive")
		(11 "B.Adhes" user "B.Adhesive")
		(13 "F.Paste" user)
		(15 "B.Paste" user)
		(5 "F.SilkS" user "F.Silkscreen")
		(7 "B.SilkS" user "B.Silkscreen")
		(1 "F.Mask" user)
		(3 "B.Mask" user)
		(17 "Dwgs.User" user "User.Drawings")
		(19 "Cmts.User" user "User.Comments")
		(21 "Eco1.User" user "User.Eco1")
		(23 "Eco2.User" user "User.Eco2")
		(25 "Edge.Cuts" user)
		(27 "Margin" user)
		(31 "F.CrtYd" user "F.Courtyard")
		(29 "B.CrtYd" user "B.Courtyard")
		(35 "F.Fab" user)
		(33 "B.Fab" user)
	)
	(footprint "antmicro-footprints:C_0805_2012Metric"
		(layer "F.Cu")
		(at 106.4875 75.225)
		(descr "Capacitor SMD 0805")
		(tags "capacitor SMD 0805")
		(property "Reference" "C11"
			(at -1.0875 1.975 0)
			(unlocked yes)
			(layer "F.SilkS")
			(effects
				(font
					(size 0.7 0.7)
					(thickness 0.15)
				)
				(justify left bottom)
			)
		)
		(property "Value" "C_22u_25V_0805"
			(at -2.055717 1.963152 0)
			(layer "F.Fab")
			(effects
				(font
					(size 0.7 0.7)
					(thickness 0.15)
				)
				(justify left bottom)
			)
		)
		(property "Author" "Antmicro"
			(at 0 0 0)
			(layer "F.Fab")
			(hide yes)
			(effects
				(font
					(size 1 1)
					(thickness 0.15)
				)
			)
		)
		(property "Dielectric" ""
			(at 0 0 0)
			(layer "F.Fab")
			(hide yes)
			(effects
				(font
					(size 1 1)
					(thickness 0.15)
				)
			)
		)
		(property "License" "Apache-2.0"
			(at 0 0 0)
			(layer "F.Fab")
			(hide yes)
			(effects
				(font
					(size 1 1)
					(thickness 0.15)
				)
			)
		)
		(property "MPN" "CL21A226MAYNNNE"
			(at 0 0 0)
			(layer "F.Fab")
			(hide yes)
			(effects
				(font
					(size 1 1)
					(thickness 0.15)
				)
			)
		)
		(property "Manufacturer" "Samsung Electro-Mechanics"
			(at 0 0 0)
			(layer "F.Fab")
			(hide yes)
			(effects
				(font
					(size 1 1)
					(thickness 0.15)
				)
			)
		)
		(property "Val" "22u_25V"
			(at 0 0 0)
			(layer "F.Fab")
			(hide yes)
			(effects
				(font
					(size 1 1)
					(thickness 0.15)
				)
			)
		)
		(property "Voltage" ""
			(at 0 0 0)
			(layer "F.Fab")
			(hide yes)
			(effects
				(font
					(size 1 1)
					(thickness 0.15)
				)
			)
		)
		(sheetname "Power supply")
		(sheetfile "power_supply.kicad_sch")
		(attr smd)
		(fp_line
			(start -0.3 -0.8)
			(end 0.3 -0.8)
			(stroke
				(width 0.15)
				(type solid)
			)
			(layer "F.SilkS")
		)
		(fp_line
			(start -0.3 0.8)
			(end 0.3 0.8)
			(stroke
				(width 0.15)
				(type solid)
			)
			(layer "F.SilkS")
		)
		(fp_rect
			(start -1.9 -0.93)
			(end 1.9 0.93)
			(stroke
				(width 0.05)
				(type solid)
			)
			(fill no)
			(layer "F.CrtYd")
		)
		(fp_rect
			(start -0.95 -0.675)
			(end 0.95 0.675)
			(stroke
				(width 0.15)
				(type solid)
			)
			(fill no)
			(layer "F.Fab")
		)
		(pad "1" smd rect
			(at -1.05 0)
			(size 1.2 1.2)
			(layers "F.Cu" "F.Mask" "F.Paste")
			(net 14 "GND")
			(pintype "passive")
		)
		(pad "2" smd rect
			(at 1.05 0)
			(size 1.2 1.2)
			(layers "F.Cu" "F.Mask" "F.Paste")
			(net 5 "+5V")
			(pintype "passive")
		)
	)
	(footprint "antmicro-footprints:C_0603_1608Metric"
		(layer "F.Cu")
		(at 105.425 61.075 180)
		(descr "Capacitor SMD 0603")
		(tags "capacitor 0603")
		(property "Reference" "C14"
			(at 1 -1.35 0)
			(unlocked yes)
			(layer "F.SilkS")
			(effects
				(font
					(size 0.7 0.7)
					(thickness 0.15)
				)
				(justify right bottom)
			)
		)
		(property "Value" "C_22u_0603"
			(at -1.42757 1.770288 0)
			(layer "F.Fab")
			(effects
				(font
					(size 0.7 0.7)
					(thickness 0.15)
				)
				(justify right bottom)
			)
		)
		(property "Author" "Antmicro"
			(at 210.85 122.15 0)
			(layer "F.Fab")
			(hide yes)
			(effects
				(font
					(size 1 1)
					(thickness 0.15)
				)
			)
		)
		(property "Dielectric" ""
			(at 210.85 122.15 0)
			(layer "F.Fab")
			(hide yes)
			(effects
				(font
					(size 1 1)
					(thickness 0.15)
				)
			)
		)
		(property "License" "Apache-2.0"
			(at 210.85 122.15 0)
			(layer "F.Fab")
			(hide yes)
			(effects
				(font
					(size 1 1)
					(thickness 0.15)
				)
			)
		)
		(property "MPN" "GRM188R60J226MEA0D"
			(at 210.85 122.15 0)
			(layer "F.Fab")
			(hide yes)
			(effects
				(font
					(size 1 1)
					(thickness 0.15)
				)
			)
		)
		(property "Manufacturer" "Murata"
			(at 210.85 122.15 0)
			(layer "F.Fab")
			(hide yes)
			(effects
				(font
					(size 1 1)
					(thickness 0.15)
				)
			)
		)
		(property "Val" "22u"
			(at 210.85 122.15 0)
			(layer "F.Fab")
			(hide yes)
			(effects
				(font
					(size 1 1)
					(thickness 0.15)
				)
			)
		)
		(property "Voltage" ""
			(at 210.85 122.15 0)
			(layer "F.Fab")
			(hide yes)
			(effects
				(font
					(size 1 1)
					(thickness 0.15)
				)
			)
		)
		(sheetname "Power supply")
		(sheetfile "power_supply.kicad_sch")
		(attr smd)
		(fp_line
			(start -0.3 0.3)
			(end 0.3 0.3)
			(stroke
				(width 0.15)
				(type solid)
			)
			(layer "F.SilkS")
		)
		(fp_line
			(start -0.3 -0.3)
			(end 0.3 -0.3)
			(stroke
				(width 0.15)
				(type solid)
			)
			(layer "F.SilkS")
		)
		(fp_rect
			(start -1.24 -0.7)
			(end 1.24 0.7)
			(stroke
				(width 0.05)
				(type solid)
			)
			(fill no)
			(layer "F.CrtYd")
		)
		(fp_rect
			(start -0.8 -0.4)
			(end 0.8 0.4)
			(stroke
				(width 0.15)
				(type solid)
			)
			(fill no)
			(layer "F.Fab")
		)
		(pad "1" smd roundrect
			(at -0.7 0 180)
			(size 0.6 0.8)
			(layers "F.Cu" "F.Mask" "F.Paste")
			(roundrect_rratio 0.2)
			(net 14 "GND")
			(pintype "passive")
		)
		(pad "2" smd roundrect
			(at 0.7 0 180)
			(size 0.6 0.8)
			(layers "F.Cu" "F.Mask" "F.Paste")
			(roundrect_rratio 0.2)
			(net 7 "/Power supply/VOUT1")
			(pintype "passive")
		)
	)
	(footprint "antmicro-footprints:R_0402_1005Metric"
		(layer "F.Cu")
		(at 135.15 91.35 90)
		(descr "Resistor SMD 0402")
		(tags "resistor SMD 0402")
		(property "Reference" "R16"
			(at -1.122484 -0.772697 90)
			(unlocked yes)
			(layer "F.SilkS")
			(effects
				(font
					(size 0.7 0.7)
					(thickness 0.15)
				)
				(justify left bottom)
			)
		)
		(property "Value" "R_100R_0402"
			(at -1.011843 1.772047 90)
			(layer "F.Fab")
			(effects
				(font
					(size 0.7 0.7)
					(thickness 0.15)
				)
				(justify left bottom)
			)
		)
		(property "Author" "Antmicro"
			(at 226.5 -43.8 0)
			(layer "F.Fab")
			(hide yes)
			(effects
				(font
					(size 1 1)
					(thickness 0.15)
				)
			)
		)
		(property "License" "Apache-2.0"
			(at 226.5 -43.8 0)
			(layer "F.Fab")
			(hide yes)
			(effects
				(font
					(size 1 1)
					(thickness 0.15)
				)
			)
		)
		(property "MPN" "CR0402-FX-1000GLF"
			(at 226.5 -43.8 0)
			(layer "F.Fab")
			(hide yes)
			(effects
				(font
					(size 1 1)
					(thickness 0.15)
				)
			)
		)
		(property "Manufacturer" "Bourns"
			(at 226.5 -43.8 0)
			(layer "F.Fab")
			(hide yes)
			(effects
				(font
					(size 1 1)
					(thickness 0.15)
				)
			)
		)
		(property "Tolerance" "1%"
			(at 226.5 -43.8 0)
			(layer "F.Fab")
			(hide yes)
			(effects
				(font
					(size 1 1)
					(thickness 0.15)
				)
			)
		)
		(property "Val" "100R"
			(at 226.5 -43.8 0)
			(layer "F.Fab")
			(hide yes)
			(effects
				(font
					(size 1 1)
					(thickness 0.15)
				)
			)
		)
		(sheetname "Translators")
		(sheetfile "translators.kicad_sch")
		(attr smd)
		(fp_rect
			(start -0.93 -0.47)
			(end 0.93 0.47)
			(stroke
				(width 0.05)
				(type solid)
			)
			(fill no)
			(layer "F.CrtYd")
		)
		(fp_rect
			(start -0.5 -0.25)
			(end 0.5 0.25)
			(stroke
				(width 0.15)
				(type solid)
			)
			(fill no)
			(layer "F.Fab")
		)
		(pad "1" smd roundrect
			(at -0.485 0 90)
			(size 0.59 0.64)
			(layers "F.Cu" "F.Mask" "F.Paste")
			(roundrect_rratio 0.25)
			(net 156 "/SODIMM/LPDDR5_IN_A.CK_P")
			(pintype "passive")
		)
		(pad "2" smd roundrect
			(at 0.485 0 90)
			(size 0.59 0.64)
			(layers "F.Cu" "F.Mask" "F.Paste")
			(roundrect_rratio 0.25)
			(net 49 "/LPDDR5/LPDDR5_A.CK_P")
			(pintype "passive")
		)
	)
	(footprint "antmicro-footprints:R_0402_1005Metric"
		(layer "F.Cu")
		(at 103.2875 72.725 180)
		(descr "Resistor SMD 0402")
		(tags "resistor SMD 0402")
		(property "Reference" "R39"
			(at -0.9125 -2.475 0)
			(unlocked yes)
			(layer "F.SilkS")
			(effects
				(font
					(size 0.7 0.7)
					(thickness 0.15)
				)
				(justify right bottom)
			)
		)
		(property "Value" "R_100k_0402"
			(at -1.011843 1.772047 0)
			(layer "F.Fab")
			(effects
				(font
					(size 0.7 0.7)
					(thickness 0.15)
				)
				(justify right bottom)
			)
		)
		(property "Author" "Antmicro"
			(at 206.575 145.45 0)
			(layer "F.Fab")
			(hide yes)
			(effects
				(font
					(size 1 1)
					(thickness 0.15)
				)
			)
		)
		(property "License" "Apache-2.0"
			(at 206.575 145.45 0)
			(layer "F.Fab")
			(hide yes)
			(effects
				(font
					(size 1 1)
					(thickness 0.15)
				)
			)
		)
		(property "MPN" "CR0402-FX-1003GLF"
			(at 206.575 145.45 0)
			(layer "F.Fab")
			(hide yes)
			(effects
				(font
					(size 1 1)
					(thickness 0.15)
				)
			)
		)
		(property "Manufacturer" "Bourns"
			(at 206.575 145.45 0)
			(layer "F.Fab")
			(hide yes)
			(effects
				(font
					(size 1 1)
					(thickness 0.15)
				)
			)
		)
		(property "Tolerance" "1%"
			(at 206.575 145.45 0)
			(layer "F.Fab")
			(hide yes)
			(effects
				(font
					(size 1 1)
					(thickness 0.15)
				)
			)
		)
		(property "Val" "100k"
			(at 206.575 145.45 0)
			(layer "F.Fab")
			(hide yes)
			(effects
				(font
					(size 1 1)
					(thickness 0.15)
				)
			)
		)
		(sheetname "Power supply")
		(sheetfile "power_supply.kicad_sch")
		(attr smd)
		(fp_rect
			(start -0.93 -0.47)
			(end 0.93 0.47)
			(stroke
				(width 0.05)
				(type solid)
			)
			(fill no)
			(layer "F.CrtYd")
		)
		(fp_rect
			(start -0.5 -0.25)
			(end 0.5 0.25)
			(stroke
				(width 0.15)
				(type solid)
			)
			(fill no)
			(layer "F.Fab")
		)
		(pad "1" smd roundrect
			(at -0.485 0 180)
			(size 0.59 0.64)
			(layers "F.Cu" "F.Mask" "F.Paste")
			(roundrect_rratio 0.25)
			(net 73 "/Power supply/FB4")
			(pintype "passive")
		)
		(pad "2" smd roundrect
			(at 0.485 0 180)
			(size 0.59 0.64)
			(layers "F.Cu" "F.Mask" "F.Paste")
			(roundrect_rratio 0.25)
			(net 10 "/Power supply/VOUT4")
			(pintype "passive")
		)
	)
	(footprint "antmicro-footprints:R_0402_1005Metric"
		(layer "F.Cu")
		(at 167.575 66.45 180)
		(descr "Resistor SMD 0402")
		(tags "resistor SMD 0402")
		(property "Reference" "R50"
			(at -1.125 -9.05 0)
			(unlocked yes)
			(layer "F.SilkS")
			(effects
				(font
					(size 0.7 0.7)
					(thickness 0.15)
				)
				(justify right bottom)
			)
		)
		(property "Value" "R_3k9_0402"
			(at -1.011843 1.772047 0)
			(layer "F.Fab")
			(effects
				(font
					(size 0.7 0.7)
					(thickness 0.15)
				)
				(justify right bottom)
			)
		)
		(property "Author" "Antmicro"
			(at 335.15 132.9 0)
			(layer "F.Fab")
			(hide yes)
			(effects
				(font
					(size 1 1)
					(thickness 0.15)
				)
			)
		)
		(property "License" "Apache-2.0"
			(at 335.15 132.9 0)
			(layer "F.Fab")
			(hide yes)
			(effects
				(font
					(size 1 1)
					(thickness 0.15)
				)
			)
		)
		(property "MPN" "CR0402-FX-3901GLF"
			(at 335.15 132.9 0)
			(layer "F.Fab")
			(hide yes)
			(effects
				(font
					(size 1 1)
					(thickness 0.15)
				)
			)
		)
		(property "Manufacturer" "Bourns"
			(at 335.15 132.9 0)
			(layer "F.Fab")
			(hide yes)
			(effects
				(font
					(size 1 1)
					(thickness 0.15)
				)
			)
		)
		(property "Tolerance" "1%"
			(at 335.15 132.9 0)
			(layer "F.Fab")
			(hide yes)
			(effects
				(font
					(size 1 1)
					(thickness 0.15)
				)
			)
		)
		(property "Val" "3k9"
			(at 335.15 132.9 0)
			(layer "F.Fab")
			(hide yes)
			(effects
				(font
					(size 1 1)
					(thickness 0.15)
				)
			)
		)
		(sheetname "Power supply")
		(sheetfile "power_supply.kicad_sch")
		(attr smd)
		(fp_rect
			(start -0.93 -0.47)
			(end 0.93 0.47)
			(stroke
				(width 0.05)
				(type solid)
			)
			(fill no)
			(layer "F.CrtYd")
		)
		(fp_rect
			(start -0.5 -0.25)
			(end 0.5 0.25)
			(stroke
				(width 0.15)
				(type solid)
			)
			(fill no)
			(layer "F.Fab")
		)
		(pad "1" smd roundrect
			(at -0.485 0 180)
			(size 0.59 0.64)
			(layers "F.Cu" "F.Mask" "F.Paste")
			(roundrect_rratio 0.25)
			(net 14 "GND")
			(pintype "passive")
		)
		(pad "2" smd roundrect
			(at 0.485 0 180)
			(size 0.59 0.64)
			(layers "F.Cu" "F.Mask" "F.Paste")
			(roundrect_rratio 0.25)
			(net 52 "Net-(POT1-Pad2)")
			(pintype "passive")
		)
	)
	(footprint "antmicro-footprints:R_0402_1005Metric"
		(layer "F.Cu")
		(at 101.7875 66.225 90)
		(descr "Resistor SMD 0402")
		(tags "resistor SMD 0402")
		(property "Reference" "R34"
			(at 0.825 0.4125 90)
			(unlocked yes)
			(layer "F.SilkS")
			(effects
				(font
					(size 0.7 0.7)
					(thickness 0.15)
				)
				(justify left bottom)
			)
		)
		(property "Value" "R_49k9_0402"
			(at -1.011843 1.772047 90)
			(layer "F.Fab")
			(effects
				(font
					(size 0.7 0.7)
					(thickness 0.15)
				)
				(justify left bottom)
			)
		)
		(property "Author" "Antmicro"
			(at 168.0125 -35.5625 0)
			(layer "F.Fab")
			(hide yes)
			(effects
				(font
					(size 1 1)
					(thickness 0.15)
				)
			)
		)
		(property "License" "Apache-2.0"
			(at 168.0125 -35.5625 0)
			(layer "F.Fab")
			(hide yes)
			(effects
				(font
					(size 1 1)
					(thickness 0.15)
				)
			)
		)
		(property "MPN" "CR0402-FX-4992GLF"
			(at 168.0125 -35.5625 0)
			(layer "F.Fab")
			(hide yes)
			(effects
				(font
					(size 1 1)
					(thickness 0.15)
				)
			)
		)
		(property "Manufacturer" "Bourns"
			(at 168.0125 -35.5625 0)
			(layer "F.Fab")
			(hide yes)
			(effects
				(font
					(size 1 1)
					(thickness 0.15)
				)
			)
		)
		(property "Tolerance" "1%"
			(at 168.0125 -35.5625 0)
			(layer "F.Fab")
			(hide yes)
			(effects
				(font
					(size 1 1)
					(thickness 0.15)
				)
			)
		)
		(property "Val" "49k9"
			(at 168.0125 -35.5625 0)
			(layer "F.Fab")
			(hide yes)
			(effects
				(font
					(size 1 1)
					(thickness 0.15)
				)
			)
		)
		(sheetname "Power supply")
		(sheetfile "power_supply.kicad_sch")
		(attr smd)
		(fp_rect
			(start -0.93 -0.47)
			(end 0.93 0.47)
			(stroke
				(width 0.05)
				(type solid)
			)
			(fill no)
			(layer "F.CrtYd")
		)
		(fp_rect
			(start -0.5 -0.25)
			(end 0.5 0.25)
			(stroke
				(width 0.15)
				(type solid)
			)
			(fill no)
			(layer "F.Fab")
		)
		(pad "1" smd roundrect
			(at -0.485 0 90)
			(size 0.59 0.64)
			(layers "F.Cu" "F.Mask" "F.Paste")
			(roundrect_rratio 0.25)
			(net 70 "/Power supply/FB1")
			(pintype "passive")
		)
		(pad "2" smd roundrect
			(at 0.485 0 90)
			(size 0.59 0.64)
			(layers "F.Cu" "F.Mask" "F.Paste")
			(roundrect_rratio 0.25)
			(net 14 "GND")
			(pintype "passive")
		)
	)
	(footprint "antmicro-footprints:R_0402_1005Metric"
		(layer "F.Cu")
		(at 146.05 93.8 90)
		(descr "Resistor SMD 0402")
		(tags "resistor SMD 0402")
		(property "Reference" "R1"
			(at -0.975 1.4 90)
			(layer "F.SilkS")
			(effects
				(font
					(size 0.7 0.7)
					(thickness 0.15)
				)
				(justify left bottom)
			)
		)
		(property "Value" "R_0R_0402"
			(at -1.011843 1.772047 90)
			(layer "F.Fab")
			(effects
				(font
					(size 0.7 0.7)
					(thickness 0.15)
				)
				(justify left bottom)
			)
		)
		(property "Author" "Antmicro"
			(at 239.85 -52.25 0)
			(layer "F.Fab")
			(hide yes)
			(effects
				(font
					(size 1 1)
					(thickness 0.15)
				)
			)
		)
		(property "Current" "1A"
			(at 239.85 -52.25 0)
			(layer "F.Fab")
			(hide yes)
			(effects
				(font
					(size 1 1)
					(thickness 0.15)
				)
			)
		)
		(property "License" "Apache-2.0"
			(at 239.85 -52.25 0)
			(layer "F.Fab")
			(hide yes)
			(effects
				(font
					(size 1 1)
					(thickness 0.15)
				)
			)
		)
		(property "MPN" "ERJ2GE0R00X"
			(at 239.85 -52.25 0)
			(layer "F.Fab")
			(hide yes)
			(effects
				(font
					(size 1 1)
					(thickness 0.15)
				)
			)
		)
		(property "Manufacturer" "Panasonic"
			(at 239.85 -52.25 0)
			(layer "F.Fab")
			(hide yes)
			(effects
				(font
					(size 1 1)
					(thickness 0.15)
				)
			)
		)
		(property "Tolerance" ""
			(at 239.85 -52.25 0)
			(layer "F.Fab")
			(hide yes)
			(effects
				(font
					(size 1 1)
					(thickness 0.15)
				)
			)
		)
		(property "Val" "0R"
			(at 239.85 -52.25 0)
			(layer "F.Fab")
			(hide yes)
			(effects
				(font
					(size 1 1)
					(thickness 0.15)
				)
			)
		)
		(sheetfile "lpddr5-testbed.kicad_sch")
		(attr smd)
		(fp_rect
			(start -0.93 -0.47)
			(end 0.93 0.47)
			(stroke
				(width 0.05)
				(type solid)
			)
			(fill no)
			(layer "F.CrtYd")
		)
		(fp_rect
			(start -0.5 -0.25)
			(end 0.5 0.25)
			(stroke
				(width 0.15)
				(type solid)
			)
			(fill no)
			(layer "F.Fab")
		)
		(pad "1" smd roundrect
			(at -0.485 0 90)
			(size 0.59 0.64)
			(layers "F.Cu" "F.Mask" "F.Paste")
			(roundrect_rratio 0.25)
			(net 34 "/SODIMM/~{RESET}")
			(pintype "passive")
		)
		(pad "2" smd roundrect
			(at 0.485 0 90)
			(size 0.59 0.64)
			(layers "F.Cu" "F.Mask" "F.Paste")
			(roundrect_rratio 0.25)
			(net 40 "/LPDDR5/~{RESET}")
			(pintype "passive")
		)
	)
)
